(kicad_pcb
	(version 20260206)
	(generator "pcbnew")
	(generator_version "10.0")
	(general
		(thickness 1.6)
		(legacy_teardrops no)
	)
	(paper "A4")
	(title_block
		(title "peb — Lightning_PEB_BRD.brd")
		(comment 1 "Lightning (Wiwynn / Facebook NVMe JBOF) / footprint 1445 of 2563 (U1), pads 1169-1288 of 1311")
	)
	(layers
		(0 "F.Cu" signal "TOP")
		(4 "In1.Cu" signal "L2GND")
		(6 "In2.Cu" signal "L3")
		(8 "In3.Cu" signal "L4VCC")
		(10 "In4.Cu" signal "L5VCC")
		(12 "In5.Cu" signal "L6")
		(14 "In6.Cu" signal "L7GND")
		(2 "B.Cu" signal "BOTTOM")
		(9 "F.Adhes" user "F.Adhesive")
		(11 "B.Adhes" user "B.Adhesive")
		(13 "F.Paste" user "Package Geometry/Pastemask Top")
		(15 "B.Paste" user "Package Geometry/Pastemask Bottom")
		(5 "F.SilkS" user "Ref Des/Silkscreen Top")
		(7 "B.SilkS" user "Ref Des/Silkscreen Bottom")
		(1 "F.Mask" user "Board Geometry/Soldermask Top")
		(3 "B.Mask" user "Board Geometry/Soldermask Bottom")
		(17 "Dwgs.User" user "User.Drawings")
		(19 "Cmts.User" user "User.Comments")
		(21 "Eco1.User" user "User.Eco1")
		(23 "Eco2.User" user "User.Eco2")
		(25 "Edge.Cuts" user "Board Geometry/Outline")
		(27 "Margin" user)
		(31 "F.CrtYd" user "Package Geometry/Place Bound Top")
		(29 "B.CrtYd" user "Package Geometry/Place Bound Bottom")
		(35 "F.Fab" user "Ref Des/Assembly Top")
		(33 "B.Fab" user "Ref Des/Assembly Bottom")
	)
	(footprint ""
		(layer "F.Cu")
		(at 240.599976 -47.999904 -90)
		(property "Reference" "U1"
			(at 0 0 270)
			(layer "F.SilkS")
			(hide yes)
			(effects
				(font
					(size 1.27 1.27)
				)
			)
		)
		(property "Value" "PM8546A-FEIP-GP"
			(at -25.785064 -6.40334 270)
			(unlocked yes)
			(layer "F.Fab")
			(hide yes)
			(effects
				(font
					(size 1.016 1.016)
					(thickness 0.1524)
				)
			)
		)
		(property "Device Type" "BGA1311C37D5H134"
			(at -25.785064 -7.92734 270)
			(unlocked yes)
			(layer "F.Fab")
			(hide yes)
			(effects
				(font
					(size 1.016 1.016)
					(thickness 0.1524)
				)
			)
		)
		(duplicate_pad_numbers_are_jumpers no)
		(pad "U4" smd circle
			(at -14.99997 -1.999996 270)
			(size 0.4572 0.4572)
			(layers "F.Cu" "F.Mask" "F.Paste")
			(net "PCIE_RX_N46")
		)
		(pad "U5" smd circle
			(at -13.999972 -1.999996 270)
			(size 0.4572 0.4572)
			(layers "F.Cu" "F.Mask" "F.Paste")
			(net "PCIE_RX_P46")
		)
		(pad "U6" smd circle
			(at -12.999974 -1.999996 270)
			(size 0.4572 0.4572)
			(layers "F.Cu" "F.Mask" "F.Paste")
			(net "GND")
		)
		(pad "U7" smd circle
			(at -11.999976 -1.999996 270)
			(size 0.4572 0.4572)
			(layers "F.Cu" "F.Mask" "F.Paste")
			(net "DUT_AVD_TX")
		)
		(pad "U8" smd circle
			(at -10.999978 -1.999996 270)
			(size 0.4572 0.4572)
			(layers "F.Cu" "F.Mask" "F.Paste")
			(net "GND")
		)
		(pad "U9" smd circle
			(at -9.99998 -1.999996 270)
			(size 0.4572 0.4572)
			(layers "F.Cu" "F.Mask" "F.Paste")
			(net "DUT_AVD_TX")
		)
		(pad "U10" smd circle
			(at -8.999982 -1.999996 270)
			(size 0.4572 0.4572)
			(layers "F.Cu" "F.Mask" "F.Paste")
			(net "GND")
		)
		(pad "U11" smd circle
			(at -7.999984 -1.999996 270)
			(size 0.4572 0.4572)
			(layers "F.Cu" "F.Mask" "F.Paste")
			(net "DUT_AVD_TX")
		)
		(pad "U12" smd circle
			(at -6.999986 -1.999996 270)
			(size 0.4572 0.4572)
			(layers "F.Cu" "F.Mask" "F.Paste")
			(net "GND")
		)
		(pad "U13" smd circle
			(at -5.999988 -1.999996 270)
			(size 0.4572 0.4572)
			(layers "F.Cu" "F.Mask" "F.Paste")
			(net "GND")
		)
		(pad "U14" smd circle
			(at -4.99999 -1.999996 270)
			(size 0.4572 0.4572)
			(layers "F.Cu" "F.Mask" "F.Paste")
			(net "DUT_VDD")
		)
		(pad "U15" smd circle
			(at -3.999992 -1.999996 270)
			(size 0.4572 0.4572)
			(layers "F.Cu" "F.Mask" "F.Paste")
			(net "GND")
		)
		(pad "U16" smd circle
			(at -2.999994 -1.999996 270)
			(size 0.4572 0.4572)
			(layers "F.Cu" "F.Mask" "F.Paste")
			(net "DUT_VDD")
		)
		(pad "U17" smd circle
			(at -1.999996 -1.999996 270)
			(size 0.4572 0.4572)
			(layers "F.Cu" "F.Mask" "F.Paste")
			(net "GND")
		)
		(pad "U18" smd circle
			(at -0.999998 -1.999996 270)
			(size 0.4572 0.4572)
			(layers "F.Cu" "F.Mask" "F.Paste")
			(net "DUT_VDD")
		)
		(pad "U19" smd circle
			(at 0 -1.999996 270)
			(size 0.4572 0.4572)
			(layers "F.Cu" "F.Mask" "F.Paste")
			(net "GND")
		)
		(pad "U20" smd circle
			(at 0.999998 -1.999996 270)
			(size 0.4572 0.4572)
			(layers "F.Cu" "F.Mask" "F.Paste")
			(net "DUT_VDD")
		)
		(pad "U21" smd circle
			(at 1.999996 -1.999996 270)
			(size 0.4572 0.4572)
			(layers "F.Cu" "F.Mask" "F.Paste")
			(net "GND")
		)
		(pad "U22" smd circle
			(at 2.999994 -1.999996 270)
			(size 0.4572 0.4572)
			(layers "F.Cu" "F.Mask" "F.Paste")
			(net "DUT_VDD")
		)
		(pad "U23" smd circle
			(at 3.999992 -1.999996 270)
			(size 0.4572 0.4572)
			(layers "F.Cu" "F.Mask" "F.Paste")
			(net "GND")
		)
		(pad "U24" smd circle
			(at 4.99999 -1.999996 270)
			(size 0.4572 0.4572)
			(layers "F.Cu" "F.Mask" "F.Paste")
			(net "DUT_VDD")
		)
		(pad "U25" smd circle
			(at 5.999988 -1.999996 270)
			(size 0.4572 0.4572)
			(layers "F.Cu" "F.Mask" "F.Paste")
			(net "GND")
		)
		(pad "U26" smd circle
			(at 6.999986 -1.999996 270)
			(size 0.4572 0.4572)
			(layers "F.Cu" "F.Mask" "F.Paste")
			(net "DUT_VDDO")
		)
		(pad "U27" smd circle
			(at 7.999984 -1.999996 270)
			(size 0.4572 0.4572)
			(layers "F.Cu" "F.Mask" "F.Paste")
			(net "LBI_DATA_7")
		)
		(pad "U28" smd circle
			(at 8.999982 -1.999996 270)
			(size 0.4572 0.4572)
			(layers "F.Cu" "F.Mask" "F.Paste")
			(net "LBI_DATA_5")
		)
		(pad "U29" smd circle
			(at 9.99998 -1.999996 270)
			(size 0.4572 0.4572)
			(layers "F.Cu" "F.Mask" "F.Paste")
			(net "LBI_DATA_6")
		)
		(pad "U30" smd circle
			(at 10.999978 -1.999996 270)
			(size 0.4572 0.4572)
			(layers "F.Cu" "F.Mask" "F.Paste")
			(net "LBI_BYTEN#")
		)
		(pad "U31" smd circle
			(at 11.999976 -1.999996 270)
			(size 0.4572 0.4572)
			(layers "F.Cu" "F.Mask" "F.Paste")
			(net "DUT_VDDO")
		)
		(pad "U32" smd circle
			(at 12.999974 -1.999996 270)
			(size 0.4572 0.4572)
			(layers "F.Cu" "F.Mask" "F.Paste")
			(net "LBI_OE#")
		)
		(pad "U33" smd circle
			(at 13.999972 -1.999996 270)
			(size 0.4572 0.4572)
			(layers "F.Cu" "F.Mask" "F.Paste")
			(net "LBI_CE#3")
		)
		(pad "U34" smd circle
			(at 14.99997 -1.999996 270)
			(size 0.4572 0.4572)
			(layers "F.Cu" "F.Mask" "F.Paste")
			(net "DUT_VDDO")
		)
		(pad "U35" smd circle
			(at 15.999968 -1.999996 270)
			(size 0.4572 0.4572)
			(layers "F.Cu" "F.Mask" "F.Paste")
			(net "GND")
		)
		(pad "U36" smd circle
			(at 16.999966 -1.999996 270)
			(size 0.4572 0.4572)
			(layers "F.Cu" "F.Mask" "F.Paste")
			(net "PCIE_RX_P0")
		)
		(pad "U37" smd circle
			(at 17.999964 -1.999996 270)
			(size 0.4572 0.4572)
			(layers "F.Cu" "F.Mask" "F.Paste")
			(net "PCIE_RX_N0")
		)
		(pad "V2" smd circle
			(at -16.999966 -0.999998 270)
			(size 0.4572 0.4572)
			(layers "F.Cu" "F.Mask" "F.Paste")
			(net "PCIE_TX_CAP_N47")
		)
		(pad "V3" smd circle
			(at -15.999968 -0.999998 270)
			(size 0.4572 0.4572)
			(layers "F.Cu" "F.Mask" "F.Paste")
			(net "PCIE_TX_CAP_P47")
		)
		(pad "V4" smd circle
			(at -14.99997 -0.999998 270)
			(size 0.4572 0.4572)
			(layers "F.Cu" "F.Mask" "F.Paste")
			(net "GND")
		)
		(pad "V5" smd circle
			(at -13.999972 -0.999998 270)
			(size 0.4572 0.4572)
			(layers "F.Cu" "F.Mask" "F.Paste")
			(net "PCIE_RX_N47")
		)
		(pad "V6" smd circle
			(at -12.999974 -0.999998 270)
			(size 0.4572 0.4572)
			(layers "F.Cu" "F.Mask" "F.Paste")
			(net "PCIE_RX_P47")
		)
		(pad "V7" smd circle
			(at -11.999976 -0.999998 270)
			(size 0.4572 0.4572)
			(layers "F.Cu" "F.Mask" "F.Paste")
			(net "GND")
		)
		(pad "V8" smd circle
			(at -10.999978 -0.999998 270)
			(size 0.4572 0.4572)
			(layers "F.Cu" "F.Mask" "F.Paste")
			(net "DUT_AVD_TX")
		)
		(pad "V9" smd circle
			(at -9.99998 -0.999998 270)
			(size 0.4572 0.4572)
			(layers "F.Cu" "F.Mask" "F.Paste")
			(net "GND")
		)
		(pad "V10" smd circle
			(at -8.999982 -0.999998 270)
			(size 0.4572 0.4572)
			(layers "F.Cu" "F.Mask" "F.Paste")
			(net "DUT_AVD_TX")
		)
		(pad "V11" smd circle
			(at -7.999984 -0.999998 270)
			(size 0.4572 0.4572)
			(layers "F.Cu" "F.Mask" "F.Paste")
			(net "GND")
		)
		(pad "V12" smd circle
			(at -6.999986 -0.999998 270)
			(size 0.4572 0.4572)
			(layers "F.Cu" "F.Mask" "F.Paste")
			(net "GND")
		)
		(pad "V13" smd circle
			(at -5.999988 -0.999998 270)
			(size 0.4572 0.4572)
			(layers "F.Cu" "F.Mask" "F.Paste")
			(net "DUT_VDD")
		)
		(pad "V14" smd circle
			(at -4.99999 -0.999998 270)
			(size 0.4572 0.4572)
			(layers "F.Cu" "F.Mask" "F.Paste")
			(net "GND")
		)
		(pad "V15" smd circle
			(at -3.999992 -0.999998 270)
			(size 0.4572 0.4572)
			(layers "F.Cu" "F.Mask" "F.Paste")
			(net "DUT_VDD")
		)
		(pad "V16" smd circle
			(at -2.999994 -0.999998 270)
			(size 0.4572 0.4572)
			(layers "F.Cu" "F.Mask" "F.Paste")
			(net "GND")
		)
		(pad "V17" smd circle
			(at -1.999996 -0.999998 270)
			(size 0.4572 0.4572)
			(layers "F.Cu" "F.Mask" "F.Paste")
			(net "DUT_VDD")
		)
		(pad "V18" smd circle
			(at -0.999998 -0.999998 270)
			(size 0.4572 0.4572)
			(layers "F.Cu" "F.Mask" "F.Paste")
			(net "GND")
		)
		(pad "V19" smd circle
			(at 0 -0.999998 270)
			(size 0.4572 0.4572)
			(layers "F.Cu" "F.Mask" "F.Paste")
			(net "DUT_VDD")
		)
		(pad "V20" smd circle
			(at 0.999998 -0.999998 270)
			(size 0.4572 0.4572)
			(layers "F.Cu" "F.Mask" "F.Paste")
			(net "GND")
		)
		(pad "V21" smd circle
			(at 1.999996 -0.999998 270)
			(size 0.4572 0.4572)
			(layers "F.Cu" "F.Mask" "F.Paste")
			(net "DUT_VDD")
		)
		(pad "V22" smd circle
			(at 2.999994 -0.999998 270)
			(size 0.4572 0.4572)
			(layers "F.Cu" "F.Mask" "F.Paste")
			(net "GND")
		)
		(pad "V23" smd circle
			(at 3.999992 -0.999998 270)
			(size 0.4572 0.4572)
			(layers "F.Cu" "F.Mask" "F.Paste")
			(net "DUT_VDD")
		)
		(pad "V24" smd circle
			(at 4.99999 -0.999998 270)
			(size 0.4572 0.4572)
			(layers "F.Cu" "F.Mask" "F.Paste")
			(net "GND")
		)
		(pad "V25" smd circle
			(at 5.999988 -0.999998 270)
			(size 0.4572 0.4572)
			(layers "F.Cu" "F.Mask" "F.Paste")
			(net "DUT_AVD_PCIE_Q")
		)
		(pad "V26" smd circle
			(at 6.999986 -0.999998 270)
			(size 0.4572 0.4572)
			(layers "F.Cu" "F.Mask" "F.Paste")
			(net "GND")
		)
		(pad "V27" smd circle
			(at 7.999984 -0.999998 270)
			(size 0.4572 0.4572)
			(layers "F.Cu" "F.Mask" "F.Paste")
			(net "LBI_WE#")
		)
		(pad "V28" smd circle
			(at 8.999982 -0.999998 270)
			(size 0.4572 0.4572)
			(layers "F.Cu" "F.Mask" "F.Paste")
			(net "DUT_VDDO_REF")
		)
		(pad "V29" smd circle
			(at 9.99998 -0.999998 270)
			(size 0.4572 0.4572)
			(layers "F.Cu" "F.Mask" "F.Paste")
			(net "Net_326")
		)
		(pad "V30" smd circle
			(at 10.999978 -0.999998 270)
			(size 0.4572 0.4572)
			(layers "F.Cu" "F.Mask" "F.Paste")
			(net "LBI_DATA15")
		)
		(pad "V31" smd circle
			(at 11.999976 -0.999998 270)
			(size 0.4572 0.4572)
			(layers "F.Cu" "F.Mask" "F.Paste")
			(net "LBI_CE#0")
		)
		(pad "V32" smd circle
			(at 12.999974 -0.999998 270)
			(size 0.4572 0.4572)
			(layers "F.Cu" "F.Mask" "F.Paste")
			(net "GND")
		)
		(pad "V33" smd circle
			(at 13.999972 -0.999998 270)
			(size 0.4572 0.4572)
			(layers "F.Cu" "F.Mask" "F.Paste")
			(net "LBI_CE#2")
		)
		(pad "V34" smd circle
			(at 14.99997 -0.999998 270)
			(size 0.4572 0.4572)
			(layers "F.Cu" "F.Mask" "F.Paste")
			(net "BOOTSTRAP_R_0")
		)
		(pad "V35" smd circle
			(at 15.999968 -0.999998 270)
			(size 0.4572 0.4572)
			(layers "F.Cu" "F.Mask" "F.Paste")
			(net "GND")
		)
		(pad "V36" smd circle
			(at 16.999966 -0.999998 270)
			(size 0.4572 0.4572)
			(layers "F.Cu" "F.Mask" "F.Paste")
			(net "GND")
		)
		(pad "V37" smd circle
			(at 17.999964 -0.999998 270)
			(size 0.4572 0.4572)
			(layers "F.Cu" "F.Mask" "F.Paste")
			(net "GND")
		)
		(pad "W1" smd circle
			(at -17.999964 0 270)
			(size 0.4572 0.4572)
			(layers "F.Cu" "F.Mask" "F.Paste")
			(net "GND")
		)
		(pad "W2" smd circle
			(at -16.999966 0 270)
			(size 0.4572 0.4572)
			(layers "F.Cu" "F.Mask" "F.Paste")
			(net "GND")
		)
		(pad "W3" smd circle
			(at -15.999968 0 270)
			(size 0.4572 0.4572)
			(layers "F.Cu" "F.Mask" "F.Paste")
			(net "GND")
		)
		(pad "W4" smd circle
			(at -14.99997 0 270)
			(size 0.4572 0.4572)
			(layers "F.Cu" "F.Mask" "F.Paste")
			(net "GND")
		)
		(pad "W5" smd circle
			(at -13.999972 0 270)
			(size 0.4572 0.4572)
			(layers "F.Cu" "F.Mask" "F.Paste")
			(net "GND")
		)
		(pad "W6" smd circle
			(at -12.999974 0 270)
			(size 0.4572 0.4572)
			(layers "F.Cu" "F.Mask" "F.Paste")
			(net "GND")
		)
		(pad "W7" smd circle
			(at -11.999976 0 270)
			(size 0.4572 0.4572)
			(layers "F.Cu" "F.Mask" "F.Paste")
			(net "DUT_AVD_TX")
		)
		(pad "W8" smd circle
			(at -10.999978 0 270)
			(size 0.4572 0.4572)
			(layers "F.Cu" "F.Mask" "F.Paste")
			(net "GND")
		)
		(pad "W9" smd circle
			(at -9.99998 0 270)
			(size 0.4572 0.4572)
			(layers "F.Cu" "F.Mask" "F.Paste")
			(net "DUT_AVD_TX")
		)
		(pad "W10" smd circle
			(at -8.999982 0 270)
			(size 0.4572 0.4572)
			(layers "F.Cu" "F.Mask" "F.Paste")
			(net "GND")
		)
		(pad "W11" smd circle
			(at -7.999984 0 270)
			(size 0.4572 0.4572)
			(layers "F.Cu" "F.Mask" "F.Paste")
			(net "DUT_AVD_TX")
		)
		(pad "W12" smd circle
			(at -6.999986 0 270)
			(size 0.4572 0.4572)
			(layers "F.Cu" "F.Mask" "F.Paste")
			(net "GND")
		)
		(pad "W13" smd circle
			(at -5.999988 0 270)
			(size 0.4572 0.4572)
			(layers "F.Cu" "F.Mask" "F.Paste")
			(net "GND")
		)
		(pad "W14" smd circle
			(at -4.99999 0 270)
			(size 0.4572 0.4572)
			(layers "F.Cu" "F.Mask" "F.Paste")
			(net "DUT_VDD")
		)
		(pad "W15" smd circle
			(at -3.999992 0 270)
			(size 0.4572 0.4572)
			(layers "F.Cu" "F.Mask" "F.Paste")
			(net "GND")
		)
		(pad "W16" smd circle
			(at -2.999994 0 270)
			(size 0.4572 0.4572)
			(layers "F.Cu" "F.Mask" "F.Paste")
			(net "DUT_VDD")
		)
		(pad "W17" smd circle
			(at -1.999996 0 270)
			(size 0.4572 0.4572)
			(layers "F.Cu" "F.Mask" "F.Paste")
			(net "GND")
		)
		(pad "W18" smd circle
			(at -0.999998 0 270)
			(size 0.4572 0.4572)
			(layers "F.Cu" "F.Mask" "F.Paste")
			(net "DUT_VDD")
		)
		(pad "W19" smd circle
			(at 0 0 270)
			(size 0.4572 0.4572)
			(layers "F.Cu" "F.Mask" "F.Paste")
			(net "GND")
		)
		(pad "W20" smd circle
			(at 0.999998 0 270)
			(size 0.4572 0.4572)
			(layers "F.Cu" "F.Mask" "F.Paste")
			(net "DUT_VDD")
		)
		(pad "W21" smd circle
			(at 1.999996 0 270)
			(size 0.4572 0.4572)
			(layers "F.Cu" "F.Mask" "F.Paste")
			(net "GND")
		)
		(pad "W22" smd circle
			(at 2.999994 0 270)
			(size 0.4572 0.4572)
			(layers "F.Cu" "F.Mask" "F.Paste")
			(net "DUT_VDD")
		)
		(pad "W23" smd circle
			(at 3.999992 0 270)
			(size 0.4572 0.4572)
			(layers "F.Cu" "F.Mask" "F.Paste")
			(net "GND")
		)
		(pad "W24" smd circle
			(at 4.99999 0 270)
			(size 0.4572 0.4572)
			(layers "F.Cu" "F.Mask" "F.Paste")
			(net "DUT_VDD")
		)
		(pad "W25" smd circle
			(at 5.999988 0 270)
			(size 0.4572 0.4572)
			(layers "F.Cu" "F.Mask" "F.Paste")
			(net "GND")
		)
		(pad "W26" smd circle
			(at 6.999986 0 270)
			(size 0.4572 0.4572)
			(layers "F.Cu" "F.Mask" "F.Paste")
			(net "DUT_VDDO_REF")
		)
		(pad "W27" smd circle
			(at 7.999984 0 270)
			(size 0.4572 0.4572)
			(layers "F.Cu" "F.Mask" "F.Paste")
			(net "BOOTSTRAP_R_6")
		)
		(pad "W28" smd circle
			(at 8.999982 0 270)
			(size 0.4572 0.4572)
			(layers "F.Cu" "F.Mask" "F.Paste")
			(net "GND")
		)
		(pad "W29" smd circle
			(at 9.99998 0 270)
			(size 0.4572 0.4572)
			(layers "F.Cu" "F.Mask" "F.Paste")
			(net "PCIE_REFCLK_H0_P")
		)
		(pad "W30" smd circle
			(at 10.999978 0 270)
			(size 0.4572 0.4572)
			(layers "F.Cu" "F.Mask" "F.Paste")
			(net "PCIE_REFCLK_H0_N")
		)
		(pad "W31" smd circle
			(at 11.999976 0 270)
			(size 0.4572 0.4572)
			(layers "F.Cu" "F.Mask" "F.Paste")
			(net "BOOTSTRAP_R_7")
		)
		(pad "W32" smd circle
			(at 12.999974 0 270)
			(size 0.4572 0.4572)
			(layers "F.Cu" "F.Mask" "F.Paste")
			(net "Net_328")
		)
		(pad "W33" smd circle
			(at 13.999972 0 270)
			(size 0.4572 0.4572)
			(layers "F.Cu" "F.Mask" "F.Paste")
			(net "Net_327")
		)
		(pad "W34" smd circle
			(at 14.99997 0 270)
			(size 0.4572 0.4572)
			(layers "F.Cu" "F.Mask" "F.Paste")
			(net "BOOTSTRAP_R_2")
		)
		(pad "W35" smd circle
			(at 15.999968 0 270)
			(size 0.4572 0.4572)
			(layers "F.Cu" "F.Mask" "F.Paste")
			(net "BOOTSTRAP_R_1")
		)
		(pad "W36" smd circle
			(at 16.999966 0 270)
			(size 0.4572 0.4572)
			(layers "F.Cu" "F.Mask" "F.Paste")
			(net "BOOTSTRAP_R_5")
		)
		(pad "W37" smd circle
			(at 17.999964 0 270)
			(size 0.4572 0.4572)
			(layers "F.Cu" "F.Mask" "F.Paste")
			(net "BOOTSTRAP_R_3")
		)
		(pad "Y2" smd circle
			(at -16.999966 0.999998 270)
			(size 0.4572 0.4572)
			(layers "F.Cu" "F.Mask" "F.Paste")
			(net "PCIE_TX_CAP_N48")
		)
		(pad "Y3" smd circle
			(at -15.999968 0.999998 270)
			(size 0.4572 0.4572)
			(layers "F.Cu" "F.Mask" "F.Paste")
			(net "PCIE_TX_CAP_P48")
		)
		(pad "Y4" smd circle
			(at -14.99997 0.999998 270)
			(size 0.4572 0.4572)
			(layers "F.Cu" "F.Mask" "F.Paste")
			(net "GND")
		)
		(pad "Y5" smd circle
			(at -13.999972 0.999998 270)
			(size 0.4572 0.4572)
			(layers "F.Cu" "F.Mask" "F.Paste")
			(net "PCIE_RX_N48")
		)
		(pad "Y6" smd circle
			(at -12.999974 0.999998 270)
			(size 0.4572 0.4572)
			(layers "F.Cu" "F.Mask" "F.Paste")
			(net "PCIE_RX_P48")
		)
		(pad "Y7" smd circle
			(at -11.999976 0.999998 270)
			(size 0.4572 0.4572)
			(layers "F.Cu" "F.Mask" "F.Paste")
			(net "GND")
		)
		(pad "Y8" smd circle
			(at -10.999978 0.999998 270)
			(size 0.4572 0.4572)
			(layers "F.Cu" "F.Mask" "F.Paste")
			(net "DUT_AVD_TX")
		)
		(pad "Y9" smd circle
			(at -9.99998 0.999998 270)
			(size 0.4572 0.4572)
			(layers "F.Cu" "F.Mask" "F.Paste")
			(net "GND")
		)
		(pad "Y10" smd circle
			(at -8.999982 0.999998 270)
			(size 0.4572 0.4572)
			(layers "F.Cu" "F.Mask" "F.Paste")
			(net "DUT_AVD_TX")
		)
		(pad "Y11" smd circle
			(at -7.999984 0.999998 270)
			(size 0.4572 0.4572)
			(layers "F.Cu" "F.Mask" "F.Paste")
			(net "GND")
		)
		(pad "Y12" smd circle
			(at -6.999986 0.999998 270)
			(size 0.4572 0.4572)
			(layers "F.Cu" "F.Mask" "F.Paste")
			(net "GND")
		)
		(pad "Y13" smd circle
			(at -5.999988 0.999998 270)
			(size 0.4572 0.4572)
			(layers "F.Cu" "F.Mask" "F.Paste")
			(net "DUT_VDD")
		)
		(pad "Y14" smd circle
			(at -4.99999 0.999998 270)
			(size 0.4572 0.4572)
			(layers "F.Cu" "F.Mask" "F.Paste")
			(net "GND")
		)
	)
)
